# TIMECARD (Time Appliance Project (Time Card)) — schematic netlist excerpt (pin names and nets, part order shuffled) for the footprints in the layout excerpt that follows; sources: Cadence DE-HDL packaged netlist, KiCad conversion of R4006-B0001-02_R01.brd

R495  RESISTOR  0OHM -  pkg SMC_0402R_H016  page 23 : \1\ = UNNAMED_12_CAPACITOR_I332_2 ; \2\ = UNNAMED_12_74HCT2G125DPTSSOP8_9
C102  CAPACITOR  0.1UF 25V 10%  pkg SMC_0402R_H022  page 24 : \1\ = XP3R3V_FPGA ; \2\ = SG

(kicad_pcb
	(version 20260206)
	(generator "pcbnew")
	(generator_version "10.0")
	(general
		(thickness 1.6)
		(legacy_teardrops no)
	)
	(paper "A4")
	(title_block
		(title "timecard-production-celestica-r4006 — R4006-B0001-02_R01.brd")
		(comment 1 "Time Appliance Project (Time Card) / footprints 930-931 of 1113")
	)
	(layers
		(0 "F.Cu" signal "TOP")
		(4 "In1.Cu" signal "L02_GND1")
		(6 "In2.Cu" signal "L03_SIG1")
		(8 "In3.Cu" signal "L04_GND2")
		(10 "In4.Cu" signal "L05_VCC1")
		(12 "In5.Cu" signal "L06_VCC2")
		(14 "In6.Cu" signal "L07_GND3")
		(16 "In7.Cu" signal "L08_SIG2")
		(18 "In8.Cu" signal "L09_GND4")
		(2 "B.Cu" signal "BOTTOM")
		(9 "F.Adhes" user "F.Adhesive")
		(11 "B.Adhes" user "B.Adhesive")
		(13 "F.Paste" user "Package Geometry/Pastemask Top")
		(15 "B.Paste" user "Package Geometry/Pastemask Bottom")
		(5 "F.SilkS" user "Ref Des/Silkscreen Top")
		(7 "B.SilkS" user "Ref Des/Silkscreen Bottom")
		(1 "F.Mask" user "Board Geometry/Soldermask Top")
		(3 "B.Mask" user "Board Geometry/Soldermask Bottom")
		(17 "Dwgs.User" user "User.Drawings")
		(19 "Cmts.User" user "User.Comments")
		(21 "Eco1.User" user "User.Eco1")
		(23 "Eco2.User" user "User.Eco2")
		(25 "Edge.Cuts" user "Board Geometry/Outline")
		(27 "Margin" user)
		(31 "F.CrtYd" user "Package Geometry/Place Bound Top")
		(29 "B.CrtYd" user "Package Geometry/Place Bound Bottom")
		(35 "F.Fab" user "Ref Des/Assembly Top")
		(33 "B.Fab" user "Ref Des/Assembly Bottom")
	)
	(footprint ""
		(layer "B.Cu")
		(at 105.918 -87.63 -90)
		(property "Reference" "C102"
			(at 0.127 -1.23063 270)
			(unlocked yes)
			(layer "B.SilkS")
			(effects
				(font
					(size 0.7874 0.5842)
					(thickness 0.1524)
				)
				(justify mirror)
			)
		)
		(property "Value" "VAL*"
			(at -0.0762 2.067306 270)
			(unlocked yes)
			(layer "B.Fab")
			(hide yes)
			(effects
				(font
					(size 0.7874 0.5842)
					(thickness 0.1524)
				)
				(justify mirror)
			)
		)
		(property "Tolerance" "TOL*"
			(at -0.0762 3.032506 270)
			(unlocked yes)
			(layer "Cmts.User")
			(hide yes)
			(effects
				(font
					(size 0.7874 0.5842)
					(thickness 0.1524)
				)
				(justify mirror)
			)
		)
		(property "User Part Number" "PARTNUM*"
			(at -0.1016 4.023106 270)
			(unlocked yes)
			(layer "Cmts.User")
			(hide yes)
			(effects
				(font
					(size 0.7874 0.5842)
					(thickness 0.1524)
				)
				(justify mirror)
			)
		)
		(property "Device Type" "CAPACITOR-G105-0B104-EK,0.1UF,A"
			(at -0.0508 1.127506 270)
			(unlocked yes)
			(layer "B.Fab")
			(hide yes)
			(effects
				(font
					(size 0.7874 0.5842)
					(thickness 0.1524)
				)
				(justify mirror)
			)
		)
		(duplicate_pad_numbers_are_jumpers no)
		(fp_line
			(start -1.143 0.5588)
			(end -1.143 -0.5588)
			(stroke
				(width 0.1)
				(type default)
			)
			(layer "B.SilkS")
		)
		(fp_line
			(start 1.143 0.5588)
			(end -1.143 0.5588)
			(stroke
				(width 0.1)
				(type default)
			)
			(layer "B.SilkS")
		)
		(fp_line
			(start -1.143 -0.5588)
			(end 1.143 -0.5588)
			(stroke
				(width 0.1)
				(type default)
			)
			(layer "B.SilkS")
		)
		(fp_line
			(start 1.143 -0.5588)
			(end 1.143 0.5588)
			(stroke
				(width 0.1)
				(type default)
			)
			(layer "B.SilkS")
		)
		(fp_poly
			(pts
				(xy 1.143 0.5588) (xy -1.143 0.5588) (xy -1.143 -0.5588) (xy 1.143 -0.5588)
			)
			(stroke
				(width 0)
				(type default)
			)
			(fill no)
			(layer "B.CrtYd")
		)
		(fp_line
			(start -0.508 0.3048)
			(end -0.508 -0.3048)
			(stroke
				(width 0.1)
				(type default)
			)
			(layer "B.Fab")
		)
		(fp_line
			(start 0.508 0.3048)
			(end -0.508 0.3048)
			(stroke
				(width 0.1)
				(type default)
			)
			(layer "B.Fab")
		)
		(fp_line
			(start -0.508 -0.3048)
			(end 0.508 -0.3048)
			(stroke
				(width 0.1)
				(type default)
			)
			(layer "B.Fab")
		)
		(fp_line
			(start 0.508 -0.3048)
			(end 0.508 0.3048)
			(stroke
				(width 0.1)
				(type default)
			)
			(layer "B.Fab")
		)
		(pad "1" smd rect
			(at 0.5334 0 90)
			(size 0.7112 0.6096)
			(layers "B.Cu" "B.Mask" "B.Paste")
			(net "XP3R3V_FPGA")
		)
		(pad "2" smd rect
			(at -0.5334 0 90)
			(size 0.7112 0.6096)
			(layers "B.Cu" "B.Mask" "B.Paste")
			(net "SG")
		)
		(zone
			(layer "B.Cu")
			(hatch none 0.5)
			(connect_pads
				(clearance 0)
			)
			(min_thickness 0.25)
			(keepout
				(tracks allowed)
				(vias not_allowed)
				(pads allowed)
				(copperpour not_allowed)
				(footprints allowed)
			)
			(placement
				(enabled no)
				(sheetname "")
			)
			(fill
				(thermal_gap 0.5)
				(thermal_bridge_width 0.5)
				(island_removal_mode 0)
			)
			(polygon
				(pts
					(xy 105.6132 -87.5538) (xy 106.2228 -87.5538) (xy 106.2228 -87.7062) (xy 105.6132 -87.7062)
				)
			)
		)
		(zone
			(layer "B.Cu")
			(hatch none 0.5)
			(connect_pads
				(clearance 0)
			)
			(min_thickness 0.25)
			(keepout
				(tracks not_allowed)
				(vias allowed)
				(pads allowed)
				(copperpour not_allowed)
				(footprints allowed)
			)
			(placement
				(enabled no)
				(sheetname "")
			)
			(fill
				(thermal_gap 0.5)
				(thermal_bridge_width 0.5)
				(island_removal_mode 0)
			)
			(polygon
				(pts
					(xy 105.6132 -87.5538) (xy 106.2228 -87.5538) (xy 106.2228 -87.7062) (xy 105.6132 -87.7062)
				)
			)
		)
	)
	(footprint ""
		(layer "B.Cu")
		(at 13.462 -52.578 90)
		(property "Reference" "R495"
			(at 0 1.10363 270)
			(unlocked yes)
			(layer "B.SilkS")
			(effects
				(font
					(size 0.7874 0.5842)
					(thickness 0.1524)
				)
				(justify mirror)
			)
		)
		(property "Value" "VAL*"
			(at -0.02032 2.13233 90)
			(unlocked yes)
			(layer "B.Fab")
			(hide yes)
			(effects
				(font
					(size 0.7874 0.5842)
					(thickness 0.1524)
				)
				(justify mirror)
			)
		)
		(property "Tolerance" "TOL*"
			(at -0.044704 3.05435 90)
			(unlocked yes)
			(layer "Cmts.User")
			(hide yes)
			(effects
				(font
					(size 0.7874 0.5842)
					(thickness 0.1524)
				)
				(justify mirror)
			)
		)
		(property "User Part Number" "PARTNUM*"
			(at -0.02032 4.024884 90)
			(unlocked yes)
			(layer "Cmts.User")
			(hide yes)
			(effects
				(font
					(size 0.7874 0.5842)
					(thickness 0.1524)
				)
				(justify mirror)
			)
		)
		(property "Device Type" "RESISTOR-G155-100R0-J0,0OHM,-"
			(at -0.008382 1.210564 90)
			(unlocked yes)
			(layer "B.Fab")
			(hide yes)
			(effects
				(font
					(size 0.7874 0.5842)
					(thickness 0.1524)
				)
				(justify mirror)
			)
		)
		(duplicate_pad_numbers_are_jumpers no)
		(fp_line
			(start 1.143 -0.5588)
			(end 1.143 0.5588)
			(stroke
				(width 0.1)
				(type default)
			)
			(layer "B.SilkS")
		)
		(fp_line
			(start -1.143 -0.5588)
			(end 1.143 -0.5588)
			(stroke
				(width 0.1)
				(type default)
			)
			(layer "B.SilkS")
		)
		(fp_line
			(start 1.143 0.5588)
			(end -1.143 0.5588)
			(stroke
				(width 0.1)
				(type default)
			)
			(layer "B.SilkS")
		)
		(fp_line
			(start -1.143 0.5588)
			(end -1.143 -0.5588)
			(stroke
				(width 0.1)
				(type default)
			)
			(layer "B.SilkS")
		)
		(fp_poly
			(pts
				(xy 1.143 0.5588) (xy -1.143 0.5588) (xy -1.143 -0.5588) (xy 1.143 -0.5588)
			)
			(stroke
				(width 0)
				(type default)
			)
			(fill no)
			(layer "B.CrtYd")
		)
		(fp_line
			(start 0.508 -0.3048)
			(end 0.508 0.3048)
			(stroke
				(width 0.1)
				(type default)
			)
			(layer "B.Fab")
		)
		(fp_line
			(start -0.508 -0.3048)
			(end 0.508 -0.3048)
			(stroke
				(width 0.1)
				(type default)
			)
			(layer "B.Fab")
		)
		(fp_line
			(start 0.508 0.3048)
			(end -0.508 0.3048)
			(stroke
				(width 0.1)
				(type default)
			)
			(layer "B.Fab")
		)
		(fp_line
			(start -0.508 0.3048)
			(end -0.508 -0.3048)
			(stroke
				(width 0.1)
				(type default)
			)
			(layer "B.Fab")
		)
		(pad "1" smd rect
			(at 0.5334 0 270)
			(size 0.7112 0.6096)
			(layers "B.Cu" "B.Mask" "B.Paste")
			(net "UNNAMED_12_CAPACITOR_I332_2")
		)
		(pad "2" smd rect
			(at -0.5334 0 270)
			(size 0.7112 0.6096)
			(layers "B.Cu" "B.Mask" "B.Paste")
			(net "UNNAMED_12_74HCT2G125DPTSSOP8_9")
		)
		(zone
			(layer "B.Cu")
			(hatch none 0.5)
			(connect_pads
				(clearance 0)
			)
			(min_thickness 0.25)
			(keepout
				(tracks not_allowed)
				(vias allowed)
				(pads allowed)
				(copperpour not_allowed)
				(footprints allowed)
			)
			(placement
				(enabled no)
				(sheetname "")
			)
			(fill
				(thermal_gap 0.5)
				(thermal_bridge_width 0.5)
				(island_removal_mode 0)
			)
			(polygon
				(pts
					(xy 13.7668 -52.6542) (xy 13.1572 -52.6542) (xy 13.1572 -52.5018) (xy 13.7668 -52.5018)
				)
			)
		)
		(zone
			(layer "B.Cu")
			(hatch none 0.5)
			(connect_pads
				(clearance 0)
			)
			(min_thickness 0.25)
			(keepout
				(tracks allowed)
				(vias not_allowed)
				(pads allowed)
				(copperpour not_allowed)
				(footprints allowed)
			)
			(placement
				(enabled no)
				(sheetname "")
			)
			(fill
				(thermal_gap 0.5)
				(thermal_bridge_width 0.5)
				(island_removal_mode 0)
			)
			(polygon
				(pts
					(xy 13.7668 -52.6542) (xy 13.1572 -52.6542) (xy 13.1572 -52.5018) (xy 13.7668 -52.5018)
				)
			)
		)
	)
)
